#ISCELL
  mstr_misc dns *
  *
#ISCELL
  mstr_symbols intel_corp_bpage *
  *
#ISCELL
  mstr_standard offpage *
  page144_i24
#ISCELL
  mstr_standard offpage *
  page144_i25
#ISCELL
  mstr_standard offpage *
  page144_i26
#ISCELL
  mstr_standard offpage *
  page144_i27
#ISCELL
  mstr_standard offpage *
  page144_i28
#ISCELL
  mstr_standard offpage *
  page144_i29
#ISCELL
  mstr_standard offpage *
  page144_i30
#ISCELL
  mstr_standard offpage *
  page144_i31
#ISCELL
  mstr_standard offpage *
  page144_i32
#ISCELL
  mstr_standard offpage *
  page144_i33
#ISCELL
  mstr_standard offpage *
  page144_i34
#ISCELL
  mstr_standard offpage *
  page144_i35
#ISCELL
  mstr_standard offpage *
  page144_i36
#ISCELL
  mstr_standard offpage *
  page144_i37
#ISCELL
  mstr_standard offpage *
  page144_i4
#ISCELL
  mstr_standard offpage *
  page144_i44
#ISCELL
  mstr_standard offpage *
  page144_i45
#ISCELL
  mstr_standard offpage *
  page144_i47
#ISCELL
  mstr_standard offpage *
  page144_i48
#ISCELL
  mstr_standard offpage *
  page144_i49
#ISCELL
  mstr_standard offpage *
  page144_i5
#ISCELL
  mstr_standard offpage *
  page144_i50
#ISCELL
  mstr_standard offpage *
  page144_i51
#ISCELL
  mstr_standard offpage *
  page144_i52
#ISCELL
  mstr_standard offpage *
  page144_i53
#ISCELL
  mstr_standard offpage *
  page144_i54
#ISCELL
  mstr_standard offpage *
  page144_i55
#ISCELL
  mstr_standard offpage *
  page144_i56
#CELL
  mstr_discrete res *
  page144_i57
#CELL
  mstr_discrete res *
  page144_i58
#CELL
  mstr_discrete res *
  page144_i59
#ISCELL
  mstr_standard offpage *
  page144_i60
#ISCELL
  mstr_standard offpage *
  page144_i66
#ISCELL
  mstr_standard offpage *
  page144_i67
#ISCELL
  mstr_standard offpage *
  page144_i68
#ISCELL
  mstr_standard offpage *
  page144_i69
#ISCELL
  mstr_standard offpage *
  page144_i70
#ISCELL
  mstr_symbols gnd *
  page144_i72
#CELL
  mstr_discrete res *
  page144_i73
#ISCELL
  mstr_standard offpage *
  page144_i74
#ISCELL
  mstr_standard offpage *
  page144_i75
#ISCELL
  mstr_standard offpage *
  page144_i76
#ISCELL
  mstr_standard offpage *
  page144_i77
#ISCELL
  mstr_standard offpage *
  page144_i78
#ISCELL
  mstr_standard offpage *
  page144_i80
#ISCELL
  mstr_standard offpage *
  page144_i81
#CELL
  mstr_discrete res *
  page144_i82
#ISCELL
  mstr_standard offpage *
  page144_i83
#ISCELL
  mstr_standard offpage *
  page144_i85
#CELL
  mstr_discrete res *
  page144_i89
#CELL
  mstr_discrete res *
  page144_i90
#ISCELL
  mstr_standard offpage *
  page144_i91
#ISCELL
  mstr_standard offpage *
  page144_i92
#ISCELL
  mstr_standard offpage *
  page144_i93
#ISCELL
  mstr_standard offpage *
  page144_i94
#CELL
  w_hdl ast2520a1-gp-gp *
  page144_i95
